(kicad_pcb
	(version 20241229)
	(generator "pcbnew")
	(generator_version "9.0")
	(general
		(thickness 1.63)
		(legacy_teardrops no)
	)
	(paper "A4")
	(title_block
		(title "CM4 Baseboard")
		(date "2026-01-05")
		(rev "1.1.1")
		(company "Antmicro Ltd")
		(comment 1 "www.antmicro.com")
		(comment 9 "footprints 286-290 of 506")
	)
	(layers
		(0 "F.Cu" signal)
		(4 "In1.Cu" power)
		(6 "In2.Cu" power)
		(8 "In3.Cu" signal)
		(10 "In4.Cu" signal)
		(2 "B.Cu" signal)
		(9 "F.Adhes" user "F.Adhesive")
		(11 "B.Adhes" user "B.Adhesive")
		(13 "F.Paste" user)
		(15 "B.Paste" user)
		(5 "F.SilkS" user "F.Silkscreen")
		(7 "B.SilkS" user "B.Silkscreen")
		(1 "F.Mask" user)
		(3 "B.Mask" user)
		(17 "Dwgs.User" user "User.Drawings")
		(19 "Cmts.User" user "User.Comments")
		(21 "Eco1.User" user "User.Eco1")
		(23 "Eco2.User" user "User.Eco2")
		(25 "Edge.Cuts" user)
		(27 "Margin" user)
		(31 "F.CrtYd" user "F.Courtyard")
		(29 "B.CrtYd" user "B.Courtyard")
		(35 "F.Fab" user)
		(33 "B.Fab" user)
	)
	(footprint "antmicro-footprints:R_0402_1005Metric"
		(layer "F.Cu")
		(at 102.067962 143.6165 180)
		(descr "Resistor SMD 0402")
		(tags "resistor SMD 0402")
		(property "Reference" "R932"
			(at -3.575 -0.475 0)
			(layer "F.SilkS")
			(effects
				(font
					(size 0.7 0.7)
					(thickness 0.15)
				)
				(justify right bottom)
			)
		)
		(property "Value" "R_10k_0402"
			(at -1.011843 1.772047 0)
			(layer "F.Fab")
			(effects
				(font
					(size 0.7 0.7)
					(thickness 0.15)
				)
				(justify right bottom)
			)
		)
		(property "Datasheet" "https://www.bourns.com/docs/product-datasheets/cr.pdf"
			(at 0 0 180)
			(layer "F.Fab")
			(hide yes)
			(effects
				(font
					(size 1.27 1.27)
					(thickness 0.15)
				)
			)
		)
		(property "Manufacturer" "Bourns"
			(at 0 0 180)
			(unlocked yes)
			(layer "F.Fab")
			(hide yes)
			(effects
				(font
					(size 1 1)
					(thickness 0.15)
				)
			)
		)
		(property "MPN" "CR0402-FX-1002GLF"
			(at 0 0 180)
			(unlocked yes)
			(layer "F.Fab")
			(hide yes)
			(effects
				(font
					(size 1 1)
					(thickness 0.15)
				)
			)
		)
		(property "Val" "10k"
			(at 0 0 180)
			(unlocked yes)
			(layer "F.Fab")
			(hide yes)
			(effects
				(font
					(size 1 1)
					(thickness 0.15)
				)
			)
		)
		(property "License" "Apache-2.0"
			(at 0 0 180)
			(unlocked yes)
			(layer "F.Fab")
			(hide yes)
			(effects
				(font
					(size 1 1)
					(thickness 0.15)
				)
			)
		)
		(property "Author" "Antmicro"
			(at 0 0 180)
			(unlocked yes)
			(layer "F.Fab")
			(hide yes)
			(effects
				(font
					(size 1 1)
					(thickness 0.15)
				)
			)
		)
		(property "Tolerance" "1%"
			(at 0 0 180)
			(unlocked yes)
			(layer "F.Fab")
			(hide yes)
			(effects
				(font
					(size 1 1)
					(thickness 0.15)
				)
			)
		)
		(sheetname "/USB/")
		(sheetfile "usb.kicad_sch")
		(attr smd exclude_from_pos_files exclude_from_bom dnp)
		(fp_rect
			(start -0.925 -0.47)
			(end 0.925 0.47)
			(stroke
				(width 0.05)
				(type default)
			)
			(fill no)
			(layer "F.CrtYd")
		)
		(fp_rect
			(start -0.5 -0.25)
			(end 0.5 0.25)
			(stroke
				(width 0.15)
				(type solid)
			)
			(fill no)
			(layer "F.Fab")
		)
		(fp_text user "${REFERENCE}"
			(at -0.95 3.168 180)
			(layer "F.Fab")
			(effects
				(font
					(size 0.7 0.7)
					(thickness 0.15)
				)
				(justify left bottom)
			)
		)
		(fp_text user "Author: Antmicro"
			(at -0.95 4.169 180)
			(layer "F.Fab")
			(effects
				(font
					(size 0.7 0.7)
					(thickness 0.15)
				)
				(justify left bottom)
			)
		)
		(fp_text user "License: Apache-2.0"
			(at -0.95 5.169 180)
			(layer "F.Fab")
			(effects
				(font
					(size 0.7 0.7)
					(thickness 0.15)
				)
				(justify left bottom)
			)
		)
		(pad "1" smd roundrect
			(at -0.48 0 180)
			(size 0.59 0.64)
			(layers "F.Cu" "F.Mask" "F.Paste")
			(roundrect_rratio 0.25)
			(net 490 "Net-(Q905-G)")
			(pintype "passive")
		)
		(pad "2" smd roundrect
			(at 0.48 0 180)
			(size 0.59 0.64)
			(layers "F.Cu" "F.Mask" "F.Paste")
			(roundrect_rratio 0.25)
			(net 27 "/USB/USB_3V3")
			(pintype "passive")
		)
	)
	(footprint "antmicro-footprints:R_0402_1005Metric"
		(layer "F.Cu")
		(at 103.817962 129.7915 90)
		(descr "Resistor SMD 0402")
		(tags "resistor SMD 0402")
		(property "Reference" "R926"
			(at -1.825 1.54 90)
			(layer "F.SilkS")
			(effects
				(font
					(size 0.7 0.7)
					(thickness 0.15)
				)
				(justify left bottom)
			)
		)
		(property "Value" "R_200R_0402"
			(at -1.011843 1.772047 90)
			(layer "F.Fab")
			(effects
				(font
					(size 0.7 0.7)
					(thickness 0.15)
				)
				(justify left bottom)
			)
		)
		(property "Datasheet" "https://www.bourns.com/docs/product-datasheets/cr.pdf"
			(at 0 0 90)
			(layer "F.Fab")
			(hide yes)
			(effects
				(font
					(size 1.27 1.27)
					(thickness 0.15)
				)
			)
		)
		(property "MPN" "CR0402-FX-2000GLF"
			(at 0 0 90)
			(unlocked yes)
			(layer "F.Fab")
			(hide yes)
			(effects
				(font
					(size 1 1)
					(thickness 0.15)
				)
			)
		)
		(property "Manufacturer" "Bourns"
			(at 0 0 90)
			(unlocked yes)
			(layer "F.Fab")
			(hide yes)
			(effects
				(font
					(size 1 1)
					(thickness 0.15)
				)
			)
		)
		(property "License" "Apache-2.0"
			(at 0 0 90)
			(unlocked yes)
			(layer "F.Fab")
			(hide yes)
			(effects
				(font
					(size 1 1)
					(thickness 0.15)
				)
			)
		)
		(property "Author" "Antmicro"
			(at 0 0 90)
			(unlocked yes)
			(layer "F.Fab")
			(hide yes)
			(effects
				(font
					(size 1 1)
					(thickness 0.15)
				)
			)
		)
		(property "Val" "200R"
			(at 0 0 90)
			(unlocked yes)
			(layer "F.Fab")
			(hide yes)
			(effects
				(font
					(size 1 1)
					(thickness 0.15)
				)
			)
		)
		(property "Tolerance" "1%"
			(at 0 0 90)
			(unlocked yes)
			(layer "F.Fab")
			(hide yes)
			(effects
				(font
					(size 1 1)
					(thickness 0.15)
				)
			)
		)
		(sheetname "/USB/")
		(sheetfile "usb.kicad_sch")
		(attr smd)
		(fp_rect
			(start -0.925 -0.47)
			(end 0.925 0.47)
			(stroke
				(width 0.05)
				(type default)
			)
			(fill no)
			(layer "F.CrtYd")
		)
		(fp_rect
			(start -0.5 -0.25)
			(end 0.5 0.25)
			(stroke
				(width 0.15)
				(type solid)
			)
			(fill no)
			(layer "F.Fab")
		)
		(fp_text user "Author: Antmicro"
			(at -0.95 4.169 90)
			(layer "F.Fab")
			(effects
				(font
					(size 0.7 0.7)
					(thickness 0.15)
				)
				(justify left bottom)
			)
		)
		(fp_text user "${REFERENCE}"
			(at -0.95 3.168 90)
			(layer "F.Fab")
			(effects
				(font
					(size 0.7 0.7)
					(thickness 0.15)
				)
				(justify left bottom)
			)
		)
		(fp_text user "License: Apache-2.0"
			(at -0.95 5.169 90)
			(layer "F.Fab")
			(effects
				(font
					(size 0.7 0.7)
					(thickness 0.15)
				)
				(justify left bottom)
			)
		)
		(pad "1" smd roundrect
			(at -0.48 0 90)
			(size 0.59 0.64)
			(layers "F.Cu" "F.Mask" "F.Paste")
			(roundrect_rratio 0.25)
			(net 10 "+5V")
			(pintype "passive")
		)
		(pad "2" smd roundrect
			(at 0.48 0 90)
			(size 0.59 0.64)
			(layers "F.Cu" "F.Mask" "F.Paste")
			(roundrect_rratio 0.25)
			(net 28 "/USB/+5V_{CAP}")
			(pintype "passive")
		)
	)
	(footprint "antmicro-footprints:LED_0603_1608Metric_G"
		(layer "F.Cu")
		(at 117.617962 135.2415 90)
		(descr "LED SMD 0603 Green")
		(tags "LED SMD 0603 Green")
		(property "Reference" "D503"
			(at 1.175 0.75 90)
			(layer "F.SilkS")
			(effects
				(font
					(size 0.7 0.7)
					(thickness 0.15)
				)
				(justify left bottom)
			)
		)
		(property "Value" "LED_G_0603_KP-1608CGCK"
			(at -0.001 1.599 90)
			(layer "F.Fab")
			(effects
				(font
					(size 0.7 0.7)
					(thickness 0.15)
				)
				(justify left bottom)
			)
		)
		(property "Datasheet" "http://www.kingbright.com/attachments/file/psearch//000/00/00/KP-1608CGCK(Ver.23B).pdf"
			(at 0 0 90)
			(layer "F.Fab")
			(hide yes)
			(effects
				(font
					(size 1.27 1.27)
					(thickness 0.15)
				)
			)
		)
		(property "MPN" "KP-1608CGCK"
			(at 0 0 90)
			(unlocked yes)
			(layer "F.Fab")
			(hide yes)
			(effects
				(font
					(size 1 1)
					(thickness 0.15)
				)
			)
		)
		(property "Manufacturer" "Kingbright"
			(at 0 0 90)
			(unlocked yes)
			(layer "F.Fab")
			(hide yes)
			(effects
				(font
					(size 1 1)
					(thickness 0.15)
				)
			)
		)
		(property "Color" "Green"
			(at 0 0 90)
			(unlocked yes)
			(layer "F.Fab")
			(hide yes)
			(effects
				(font
					(size 1 1)
					(thickness 0.15)
				)
			)
		)
		(property "Author" "Antmicro"
			(at 0 0 90)
			(unlocked yes)
			(layer "F.Fab")
			(hide yes)
			(effects
				(font
					(size 1 1)
					(thickness 0.15)
				)
			)
		)
		(property "License" "Apache-2.0"
			(at 0 0 90)
			(unlocked yes)
			(layer "F.Fab")
			(hide yes)
			(effects
				(font
					(size 1 1)
					(thickness 0.15)
				)
			)
		)
		(sheetname "/NVMe & microSD/")
		(sheetfile "nvme-micro-sd.kicad_sch")
		(attr smd)
		(fp_line
			(start 0.22 -0.35)
			(end -0.22 -0.35)
			(stroke
				(width 0.15)
				(type solid)
			)
			(layer "F.SilkS")
		)
		(fp_line
			(start -1.18 -0.319)
			(end -1.18 0.321)
			(stroke
				(width 0.15)
				(type solid)
			)
			(layer "F.SilkS")
		)
		(fp_line
			(start 0.105328 0.001008)
			(end 0.24 0.001)
			(stroke
				(width 0.1)
				(type solid)
			)
			(layer "F.SilkS")
		)
		(fp_line
			(start -0.094672 0.001008)
			(end 0.105328 -0.198992)
			(stroke
				(width 0.1)
				(type solid)
			)
			(layer "F.SilkS")
		)
		(fp_line
			(start -0.094672 0.001008)
			(end -0.24 0.001008)
			(stroke
				(width 0.1)
				(type solid)
			)
			(layer "F.SilkS")
		)
		(fp_line
			(start 0.105328 0.201008)
			(end 0.105328 -0.198992)
			(stroke
				(width 0.1)
				(type solid)
			)
			(layer "F.SilkS")
		)
		(fp_line
			(start 0.105328 0.201008)
			(end -0.094672 0.001008)
			(stroke
				(width 0.1)
				(type solid)
			)
			(layer "F.SilkS")
		)
		(fp_line
			(start -0.094672 0.201008)
			(end -0.094672 -0.198992)
			(stroke
				(width 0.1)
				(type solid)
			)
			(layer "F.SilkS")
		)
		(fp_line
			(start 0.22 0.35)
			(end -0.22 0.35)
			(stroke
				(width 0.15)
				(type solid)
			)
			(layer "F.SilkS")
		)
		(fp_rect
			(start 1.25 0.65)
			(end -1.25 -0.65)
			(stroke
				(width 0.05)
				(type solid)
			)
			(fill no)
			(layer "F.CrtYd")
		)
		(fp_line
			(start 0.201 -0.202)
			(end -0.101 0)
			(stroke
				(width 0.15)
				(type solid)
			)
			(layer "F.Fab")
		)
		(fp_line
			(start -0.199 -0.202)
			(end -0.199 0.1)
			(stroke
				(width 0.15)
				(type solid)
			)
			(layer "F.Fab")
		)
		(fp_line
			(start 0.599 0)
			(end 0.201 0)
			(stroke
				(width 0.15)
				(type solid)
			)
			(layer "F.Fab")
		)
		(fp_line
			(start 0.201 0)
			(end 0.201 -0.202)
			(stroke
				(width 0.15)
				(type solid)
			)
			(layer "F.Fab")
		)
		(fp_line
			(start -0.101 0)
			(end 0.201 0.2)
			(stroke
				(width 0.15)
				(type solid)
			)
			(layer "F.Fab")
		)
		(fp_line
			(start -0.199 0)
			(end -0.597 0)
			(stroke
				(width 0.15)
				(type solid)
			)
			(layer "F.Fab")
		)
		(fp_line
			(start 0.201 0.2)
			(end 0.201 0)
			(stroke
				(width 0.15)
				(type solid)
			)
			(layer "F.Fab")
		)
		(fp_line
			(start -0.199 0.2)
			(end -0.199 0.1)
			(stroke
				(width 0.15)
				(type solid)
			)
			(layer "F.Fab")
		)
		(fp_rect
			(start 0.848 0.4)
			(end -0.85 -0.402)
			(stroke
				(width 0.15)
				(type solid)
			)
			(fill no)
			(layer "F.Fab")
		)
		(fp_text user "Author: Antmicro"
			(at -1.4224 4.799 90)
			(layer "F.Fab")
			(effects
				(font
					(size 0.7 0.7)
					(thickness 0.15)
				)
				(justify left bottom)
			)
		)
		(fp_text user "${REFERENCE}"
			(at -1.4224 5.999 90)
			(layer "F.Fab")
			(effects
				(font
					(size 0.7 0.7)
					(thickness 0.15)
				)
				(justify left bottom)
			)
		)
		(fp_text user "License: Apache-2.0"
			(at -1.4224 3.599 90)
			(layer "F.Fab")
			(effects
				(font
					(size 0.7 0.7)
					(thickness 0.15)
				)
				(justify left bottom)
			)
		)
		(pad "1" smd roundrect
			(at -0.7 0 270)
			(size 0.8 1)
			(layers "F.Cu" "F.Mask" "F.Paste")
			(roundrect_rratio 0.2)
			(net 470 "Net-(D503-C)")
			(pinfunction "C")
			(pintype "passive")
		)
		(pad "2" smd roundrect
			(at 0.7 0 270)
			(size 0.8 1)
			(layers "F.Cu" "F.Mask" "F.Paste")
			(roundrect_rratio 0.2)
			(net 478 "Net-(D503-A)")
			(pinfunction "A")
			(pintype "passive")
		)
	)
	(footprint "antmicro-footprints:C_0402_1005Metric"
		(layer "F.Cu")
		(at 61.442962 179.1415 180)
		(descr "Capacitor SMD 0402")
		(tags "capacitor SMD 0402")
		(property "Reference" "C811"
			(at 14.192962 1.3915 0)
			(layer "F.SilkS")
			(effects
				(font
					(size 0.7 0.7)
					(thickness 0.15)
				)
				(justify right top)
			)
		)
		(property "Value" "C_12p_0402"
			(at -1.022927 2.155213 0)
			(layer "F.Fab")
			(effects
				(font
					(size 0.7 0.7)
					(thickness 0.15)
				)
				(justify right top)
			)
		)
		(property "Datasheet" "https://product.tdk.com/en/search/capacitor/ceramic/mlcc/info?part_no=CGA2B2C0G1H120J050BA"
			(at 0 0 0)
			(layer "F.Fab")
			(hide yes)
			(effects
				(font
					(size 1.27 1.27)
					(thickness 0.15)
				)
			)
		)
		(property "Description" "SMD Multilayer Ceramic Capacitor, 12 pF, 50 V, 0402 [1005 Metric], ± 5%, C0G / NP0, CGA"
			(at 0 0 0)
			(layer "F.Fab")
			(hide yes)
			(effects
				(font
					(size 1.27 1.27)
					(thickness 0.15)
				)
			)
		)
		(property "MPN" "CGA2B2C0G1H120J050BA"
			(at 0 0 180)
			(unlocked yes)
			(layer "F.Fab")
			(hide yes)
			(effects
				(font
					(size 1 1)
					(thickness 0.15)
				)
			)
		)
		(property "Manufacturer" "TDK"
			(at 0 0 180)
			(unlocked yes)
			(layer "F.Fab")
			(hide yes)
			(effects
				(font
					(size 1 1)
					(thickness 0.15)
				)
			)
		)
		(property "License" "Apache-2.0"
			(at 0 0 180)
			(unlocked yes)
			(layer "F.Fab")
			(hide yes)
			(effects
				(font
					(size 1 1)
					(thickness 0.15)
				)
			)
		)
		(property "Author" "Antmicro"
			(at 0 0 180)
			(unlocked yes)
			(layer "F.Fab")
			(hide yes)
			(effects
				(font
					(size 1 1)
					(thickness 0.15)
				)
			)
		)
		(property "Val" "12p"
			(at 0 0 180)
			(unlocked yes)
			(layer "F.Fab")
			(hide yes)
			(effects
				(font
					(size 1 1)
					(thickness 0.15)
				)
			)
		)
		(property "Voltage" ""
			(at 0 0 180)
			(unlocked yes)
			(layer "F.Fab")
			(hide yes)
			(effects
				(font
					(size 1 1)
					(thickness 0.15)
				)
			)
		)
		(property "Dielectric" ""
			(at 0 0 180)
			(unlocked yes)
			(layer "F.Fab")
			(hide yes)
			(effects
				(font
					(size 1 1)
					(thickness 0.15)
				)
			)
		)
		(sheetname "/Peripherals/")
		(sheetfile "peripherals.kicad_sch")
		(attr smd)
		(fp_rect
			(start -0.925 -0.47)
			(end 0.925 0.47)
			(stroke
				(width 0.05)
				(type default)
			)
			(fill no)
			(layer "F.CrtYd")
		)
		(fp_line
			(start 0.504 0.248)
			(end -0.494 0.248)
			(stroke
				(width 0.15)
				(type solid)
			)
			(layer "F.Fab")
		)
		(fp_line
			(start 0.504 -0.25)
			(end 0.504 0.248)
			(stroke
				(width 0.15)
				(type solid)
			)
			(layer "F.Fab")
		)
		(fp_line
			(start -0.494 0.248)
			(end -0.494 -0.25)
			(stroke
				(width 0.15)
				(type solid)
			)
			(layer "F.Fab")
		)
		(fp_line
			(start -0.494 -0.25)
			(end 0.504 -0.25)
			(stroke
				(width 0.15)
				(type solid)
			)
			(layer "F.Fab")
		)
		(fp_text user "License: Apache-2.0"
			(at -0.939 5.799 0)
			(layer "F.Fab")
			(effects
				(font
					(size 0.7 0.7)
					(thickness 0.15)
				)
				(justify right top)
			)
		)
		(fp_text user "Author: Antmicro"
			(at -0.939 3.399 0)
			(layer "F.Fab")
			(effects
				(font
					(size 0.7 0.7)
					(thickness 0.15)
				)
				(justify right top)
			)
		)
		(fp_text user "${REFERENCE}"
			(at -0.939 4.599 0)
			(layer "F.Fab")
			(effects
				(font
					(size 0.7 0.7)
					(thickness 0.15)
				)
				(justify right top)
			)
		)
		(pad "1" smd roundrect
			(at -0.48 0 180)
			(size 0.59 0.64)
			(layers "F.Cu" "F.Mask" "F.Paste")
			(roundrect_rratio 0.25)
			(net 101 "Net-(U801-ANT1)")
			(pintype "passive")
		)
		(pad "2" smd roundrect
			(at 0.48 0 180)
			(size 0.59 0.64)
			(layers "F.Cu" "F.Mask" "F.Paste")
			(roundrect_rratio 0.25)
			(net 100 "Net-(C811-Pad2)")
			(pintype "passive")
		)
	)
	(footprint "antmicro-footprints:TP_SMD_0.75mm"
		(layer "F.Cu")
		(at 93.85 133.05)
		(property "Reference" "TP919"
			(at 3.05 3.41 0)
			(layer "F.SilkS")
			(effects
				(font
					(size 0.7 0.7)
					(thickness 0.15)
				)
				(justify left bottom)
			)
		)
		(property "Value" "TP_0.75mm_SMD"
			(at 0 1.2 0)
			(layer "F.Fab")
			(effects
				(font
					(size 0.7 0.7)
					(thickness 0.15)
				)
				(justify left bottom)
			)
		)
		(property "MPN" ""
			(at 0 0 0)
			(unlocked yes)
			(layer "F.Fab")
			(hide yes)
			(effects
				(font
					(size 1 1)
					(thickness 0.15)
				)
			)
		)
		(property "Manufacturer" ""
			(at 0 0 0)
			(unlocked yes)
			(layer "F.Fab")
			(hide yes)
			(effects
				(font
					(size 1 1)
					(thickness 0.15)
				)
			)
		)
		(property "Author" "Antmicro"
			(at 0 0 0)
			(unlocked yes)
			(layer "F.Fab")
			(hide yes)
			(effects
				(font
					(size 1 1)
					(thickness 0.15)
				)
			)
		)
		(property "License" "Apache-2.0"
			(at 0 0 0)
			(unlocked yes)
			(layer "F.Fab")
			(hide yes)
			(effects
				(font
					(size 1 1)
					(thickness 0.15)
				)
			)
		)
		(sheetname "/USB/")
		(sheetfile "usb.kicad_sch")
		(attr exclude_from_pos_files exclude_from_bom)
		(fp_circle
			(center 0 0)
			(end 0.475 0)
			(stroke
				(width 0.05)
				(type default)
			)
			(fill no)
			(layer "F.CrtYd")
		)
		(fp_text user "License: Apache-2.0"
			(at -0.4 5.101 0)
			(layer "F.Fab")
			(effects
				(font
					(size 0.7 0.7)
					(thickness 0.15)
				)
				(justify left bottom)
			)
		)
		(fp_text user "${REFERENCE}"
			(at -0.4 2.7 0)
			(layer "F.Fab")
			(effects
				(font
					(size 0.7 0.7)
					(thickness 0.15)
				)
				(justify left bottom)
			)
		)
		(fp_text user "Author: Antmicro"
			(at -0.4 3.901 0)
			(layer "F.Fab")
			(effects
				(font
					(size 0.7 0.7)
					(thickness 0.15)
				)
				(justify left bottom)
			)
		)
		(pad "1" smd circle
			(at 0 0)
			(size 0.75 0.75)
			(layers "F.Cu" "F.Mask")
			(net 450 "Net-(U905-GPIO2)")
			(pinfunction "1")
			(pintype "passive")
		)
	)
)
